(kicad_pcb
	(version 20241229)
	(generator "pcbnew")
	(generator_version "9.0")
	(general
		(thickness 1.61)
		(legacy_teardrops no)
	)
	(paper "A3")
	(title_block
		(title "RDIMM DDR5 Tester")
		(date "2026-05-21")
		(rev "2.2.0")
		(company "Antmicro")
		(comment 9 "footprint 119 of 796 (U34), pads 606-672 of 676")
	)
	(layers
		(0 "F.Cu" signal)
		(4 "In1.Cu" power)
		(6 "In2.Cu" mixed)
		(8 "In3.Cu" power)
		(10 "In4.Cu" mixed)
		(12 "In5.Cu" power)
		(14 "In6.Cu" mixed)
		(16 "In7.Cu" power)
		(18 "In8.Cu" power)
		(20 "In9.Cu" mixed)
		(22 "In10.Cu" power)
		(2 "B.Cu" signal)
		(9 "F.Adhes" user "F.Adhesive")
		(11 "B.Adhes" user "B.Adhesive")
		(13 "F.Paste" user)
		(15 "B.Paste" user)
		(5 "F.SilkS" user "F.Silkscreen")
		(7 "B.SilkS" user "B.Silkscreen")
		(1 "F.Mask" user)
		(3 "B.Mask" user)
		(17 "Dwgs.User" user "User.Drawings")
		(19 "Cmts.User" user "User.Comments")
		(21 "Eco1.User" user "User.Eco1")
		(23 "Eco2.User" user "User.Eco2")
		(25 "Edge.Cuts" user)
		(27 "Margin" user)
		(31 "F.CrtYd" user "F.Courtyard")
		(29 "B.CrtYd" user "B.Courtyard")
		(35 "F.Fab" user)
		(33 "B.Fab" user)
	)
	(footprint "antmicro-footprints:BGA-676_27x27mm_Layout26x26_P1x1mm_FFVB676"
		(layer "F.Cu")
		(at 188.5 152.5 90)
		(property "Reference" "U34"
			(at -14.72 12.46 180)
			(layer "F.SilkS")
			(effects
				(font
					(size 0.7 0.7)
					(thickness 0.15)
				)
				(justify left bottom)
			)
		)
		(property "Value" "XCAU25P-2FFVB676I"
			(at 0 15.5 90)
			(layer "F.Fab")
			(effects
				(font
					(size 0.7 0.7)
					(thickness 0.15)
				)
				(justify left bottom)
			)
		)
		(property "Datasheet" "https://docs.xilinx.com/viewer/book-attachment/2PXOpPtpaABIt0fkzeBLnw/hvbsEUaOT0OxFhln7VEVyA"
			(at 0 0 90)
			(layer "F.Fab")
			(hide yes)
			(effects
				(font
					(size 1.27 1.27)
					(thickness 0.15)
				)
			)
		)
		(property "MPN" "XCAU25P-2FFVB676I"
			(at 0 0 90)
			(unlocked yes)
			(layer "F.Fab")
			(hide yes)
			(effects
				(font
					(size 1 1)
					(thickness 0.15)
				)
			)
		)
		(property "Manufacturer" "AMD-Xilinx"
			(at 0 0 90)
			(unlocked yes)
			(layer "F.Fab")
			(hide yes)
			(effects
				(font
					(size 1 1)
					(thickness 0.15)
				)
			)
		)
		(property "Author" "Antmicro"
			(at 0 0 90)
			(unlocked yes)
			(layer "F.Fab")
			(hide yes)
			(effects
				(font
					(size 1 1)
					(thickness 0.15)
				)
			)
		)
		(property "License" "Apache-2.0"
			(at 0 0 90)
			(unlocked yes)
			(layer "F.Fab")
			(hide yes)
			(effects
				(font
					(size 1 1)
					(thickness 0.15)
				)
			)
		)
		(sheetname "/FPGA Config/")
		(sheetfile "fpga-config.kicad_sch")
		(attr smd)
		(pad "V8" smd circle
			(at -5.5 4.5 90)
			(size 0.5 0.5)
			(layers "F.Cu" "F.Mask" "F.Paste")
			(net 1 "GND")
			(pinfunction "GND")
			(pintype "passive")
			(solder_mask_margin 0.075)
		)
		(pad "V9" smd circle
			(at -4.5 4.5 90)
			(size 0.5 0.5)
			(layers "F.Cu" "F.Mask" "F.Paste")
			(net 553 "+0V85")
			(pinfunction "VCCBRAM")
			(pintype "passive")
			(solder_mask_margin 0.075)
		)
		(pad "V10" smd circle
			(at -3.5 4.5 90)
			(size 0.5 0.5)
			(layers "F.Cu" "F.Mask" "F.Paste")
			(net 1 "GND")
			(pinfunction "GND")
			(pintype "passive")
			(solder_mask_margin 0.075)
		)
		(pad "V11" smd circle
			(at -2.5 4.5 90)
			(size 0.5 0.5)
			(layers "F.Cu" "F.Mask" "F.Paste")
			(net 553 "+0V85")
			(pinfunction "VCCINT")
			(pintype "passive")
			(solder_mask_margin 0.075)
		)
		(pad "V12" smd circle
			(at -1.5 4.5 90)
			(size 0.5 0.5)
			(layers "F.Cu" "F.Mask" "F.Paste")
			(net 1 "GND")
			(pinfunction "GND")
			(pintype "passive")
			(solder_mask_margin 0.075)
		)
		(pad "V13" smd circle
			(at -0.5 4.5 90)
			(size 0.5 0.5)
			(layers "F.Cu" "F.Mask" "F.Paste")
			(net 553 "+0V85")
			(pinfunction "VCCINT")
			(pintype "passive")
			(solder_mask_margin 0.075)
		)
		(pad "V14" smd circle
			(at 0.5 4.5 90)
			(size 0.5 0.5)
			(layers "F.Cu" "F.Mask" "F.Paste")
			(net 1 "GND")
			(pinfunction "GND")
			(pintype "passive")
			(solder_mask_margin 0.075)
		)
		(pad "V15" smd circle
			(at 1.5 4.5 90)
			(size 0.5 0.5)
			(layers "F.Cu" "F.Mask" "F.Paste")
			(net 553 "+0V85")
			(pinfunction "VCCINT")
			(pintype "passive")
			(solder_mask_margin 0.075)
		)
		(pad "V16" smd circle
			(at 2.5 4.5 90)
			(size 0.5 0.5)
			(layers "F.Cu" "F.Mask" "F.Paste")
			(net 1 "GND")
			(pinfunction "GND")
			(pintype "passive")
			(solder_mask_margin 0.075)
		)
		(pad "V17" smd circle
			(at 3.5 4.5 90)
			(size 0.5 0.5)
			(layers "F.Cu" "F.Mask" "F.Paste")
			(net 553 "+0V85")
			(pinfunction "VCCINT")
			(pintype "passive")
			(solder_mask_margin 0.075)
		)
		(pad "V18" smd circle
			(at 4.5 4.5 90)
			(size 0.5 0.5)
			(layers "F.Cu" "F.Mask" "F.Paste")
			(net 536 "/FPGA banks HP/VREF_65")
			(pinfunction "VREF_65")
			(pintype "input")
			(solder_mask_margin 0.075)
		)
		(pad "V19" smd circle
			(at 5.5 4.5 90)
			(size 0.5 0.5)
			(layers "F.Cu" "F.Mask" "F.Paste")
			(net 121 "/DDR5 RDIMM/A.DQS4_N")
			(pinfunction "IO_L1N_T0L_N1_DBC_RS1_65")
			(pintype "bidirectional")
			(die_length 12.006)
			(solder_mask_margin 0.075)
		)
		(pad "V20" smd circle
			(at 6.5 4.5 90)
			(size 0.5 0.5)
			(layers "F.Cu" "F.Mask" "F.Paste")
			(net 1 "GND")
			(pinfunction "GND")
			(pintype "passive")
			(solder_mask_margin 0.075)
		)
		(pad "V21" smd circle
			(at 7.5 4.5 90)
			(size 0.5 0.5)
			(layers "F.Cu" "F.Mask" "F.Paste")
			(net 235 "/DDR5 RDIMM/A.DQS9_P")
			(pinfunction "IO_L4P_T0U_N6_DBC_AD7P_A24_65")
			(pintype "bidirectional")
			(die_length 9.873)
			(solder_mask_margin 0.075)
		)
		(pad "V22" smd circle
			(at 8.5 4.5 90)
			(size 0.5 0.5)
			(layers "F.Cu" "F.Mask" "F.Paste")
			(net 234 "/DDR5 RDIMM/A.DQS9_N")
			(pinfunction "IO_L4N_T0U_N7_DBC_AD7N_A25_65")
			(pintype "bidirectional")
			(die_length 9.665)
			(solder_mask_margin 0.075)
		)
		(pad "V23" smd circle
			(at 9.5 4.5 90)
			(size 0.5 0.5)
			(layers "F.Cu" "F.Mask" "F.Paste")
			(net 192 "/DDR5 RDIMM/A.CA1")
			(pinfunction "IO_L11P_T1U_N8_GC_A10_D26_65")
			(pintype "bidirectional")
			(die_length 12.46)
			(solder_mask_margin 0.075)
		)
		(pad "V24" smd circle
			(at 10.5 4.5 90)
			(size 0.5 0.5)
			(layers "F.Cu" "F.Mask" "F.Paste")
			(net 77 "/DDR5 RDIMM/A.CA6")
			(pinfunction "IO_L12P_T1U_N10_GC_A08_D24_65")
			(pintype "bidirectional")
			(die_length 11.139)
			(solder_mask_margin 0.075)
		)
		(pad "V25" smd circle
			(at 11.5 4.5 90)
			(size 0.5 0.5)
			(layers "F.Cu" "F.Mask" "F.Paste")
			(net 1 "GND")
			(pinfunction "GND")
			(pintype "passive")
			(solder_mask_margin 0.075)
		)
		(pad "V26" smd circle
			(at 12.5 4.5 90)
			(size 0.5 0.5)
			(layers "F.Cu" "F.Mask" "F.Paste")
			(net 85 "/DDR5 RDIMM/CTRL.DLBDQS")
			(pinfunction "IO_L16N_T2U_N7_QBC_AD3N_A01_D17_65")
			(pintype "bidirectional")
			(die_length 11.807)
			(solder_mask_margin 0.075)
		)
		(pad "W1" smd circle
			(at -12.5 5.5 90)
			(size 0.5 0.5)
			(layers "F.Cu" "F.Mask" "F.Paste")
			(net 1 "GND")
			(pinfunction "GND")
			(pintype "passive")
			(solder_mask_margin 0.075)
		)
		(pad "W2" smd circle
			(at -11.5 5.5 90)
			(size 0.5 0.5)
			(layers "F.Cu" "F.Mask" "F.Paste")
			(net 1 "GND")
			(pinfunction "GND")
			(pintype "passive")
			(solder_mask_margin 0.075)
		)
		(pad "W3" smd circle
			(at -10.5 5.5 90)
			(size 0.5 0.5)
			(layers "F.Cu" "F.Mask" "F.Paste")
			(net 1 "GND")
			(pinfunction "GND")
			(pintype "passive")
			(solder_mask_margin 0.075)
		)
		(pad "W4" smd circle
			(at -9.5 5.5 90)
			(size 0.5 0.5)
			(layers "F.Cu" "F.Mask" "F.Paste")
			(net 26 "/FPGA MGT Interface/GTY_225_TX1_N")
			(pinfunction "MGTYTXN1_225")
			(pintype "output")
			(die_length 10.352)
			(solder_mask_margin 0.075)
		)
		(pad "W5" smd circle
			(at -8.5 5.5 90)
			(size 0.5 0.5)
			(layers "F.Cu" "F.Mask" "F.Paste")
			(net 18 "/FPGA MGT Interface/GTY_225_TX1_P")
			(pinfunction "MGTYTXP1_225")
			(pintype "output")
			(die_length 10.335)
			(solder_mask_margin 0.075)
		)
		(pad "W6" smd circle
			(at -7.5 5.5 90)
			(size 0.5 0.5)
			(layers "F.Cu" "F.Mask" "F.Paste")
			(net 1 "GND")
			(pinfunction "GND")
			(pintype "passive")
			(solder_mask_margin 0.075)
		)
		(pad "W7" smd circle
			(at -6.5 5.5 90)
			(size 0.5 0.5)
			(layers "F.Cu" "F.Mask" "F.Paste")
			(net 820 "+0V9_MGTAVCC")
			(pinfunction "MGTAVCC_R")
			(pintype "passive")
			(solder_mask_margin 0.075)
		)
		(pad "W8" smd circle
			(at -5.5 5.5 90)
			(size 0.5 0.5)
			(layers "F.Cu" "F.Mask" "F.Paste")
			(net 1 "GND")
			(pinfunction "GND")
			(pintype "passive")
			(solder_mask_margin 0.075)
		)
		(pad "W9" smd circle
			(at -4.5 5.5 90)
			(size 0.5 0.5)
			(layers "F.Cu" "F.Mask" "F.Paste")
			(net 40 "/FPGA Config/PUDC_B")
			(pinfunction "PUDC_B_0")
			(pintype "input")
			(die_length 12.177)
			(solder_mask_margin 0.075)
		)
		(pad "W10" smd circle
			(at -3.5 5.5 90)
			(size 0.5 0.5)
			(layers "F.Cu" "F.Mask" "F.Paste")
			(net 341 "/FPGA Config/INIT_B")
			(pinfunction "INIT_B_0")
			(pintype "bidirectional")
			(die_length 11.957)
			(solder_mask_margin 0.075)
		)
		(pad "W11" smd circle
			(at -2.5 5.5 90)
			(size 0.5 0.5)
			(layers "F.Cu" "F.Mask" "F.Paste")
			(net 1 "GND")
			(pinfunction "RSVDGND")
			(pintype "input")
			(die_length 12.269)
			(solder_mask_margin 0.075)
		)
		(pad "W12" smd circle
			(at -1.5 5.5 90)
			(size 0.5 0.5)
			(layers "F.Cu" "F.Mask" "F.Paste")
			(net 746 "/FPGA Config/FPGA_PWR.SDA")
			(pinfunction "IO_L12P_AD0P_84")
			(pintype "bidirectional")
			(die_length 10.067)
			(solder_mask_margin 0.075)
		)
		(pad "W13" smd circle
			(at -0.5 5.5 90)
			(size 0.5 0.5)
			(layers "F.Cu" "F.Mask" "F.Paste")
			(net 747 "/FPGA Config/FPGA_PWR.SCL")
			(pinfunction "IO_L12N_AD0N_84")
			(pintype "bidirectional")
			(die_length 10.556)
			(solder_mask_margin 0.075)
		)
		(pad "W14" smd circle
			(at 0.5 5.5 90)
			(size 0.5 0.5)
			(layers "F.Cu" "F.Mask" "F.Paste")
			(net 472 "/FPGA banks HD/FPGA_DDR.SDA")
			(pinfunction "IO_L10P_AD2P_84")
			(pintype "bidirectional")
			(die_length 9.435)
			(solder_mask_margin 0.075)
		)
		(pad "W15" smd circle
			(at 1.5 5.5 90)
			(size 0.5 0.5)
			(layers "F.Cu" "F.Mask" "F.Paste")
			(net 465 "/FPGA banks HD/FPGA_DDR.SCL")
			(pinfunction "IO_L10N_AD2N_84")
			(pintype "bidirectional")
			(die_length 9.29)
			(solder_mask_margin 0.075)
		)
		(pad "W16" smd circle
			(at 2.5 5.5 90)
			(size 0.5 0.5)
			(layers "F.Cu" "F.Mask" "F.Paste")
			(net 567 "unconnected-(U34F-IO_L9P_AD3P_84-PadW16)")
			(pinfunction "IO_L9P_AD3P_84")
			(pintype "bidirectional+no_connect")
			(die_length 10.407)
			(solder_mask_margin 0.075)
		)
		(pad "W17" smd circle
			(at 3.5 5.5 90)
			(size 0.5 0.5)
			(layers "F.Cu" "F.Mask" "F.Paste")
			(net 1 "GND")
			(pinfunction "GND")
			(pintype "passive")
			(solder_mask_margin 0.075)
		)
		(pad "W18" smd circle
			(at 4.5 5.5 90)
			(size 0.5 0.5)
			(layers "F.Cu" "F.Mask" "F.Paste")
			(net 535 "/FPGA banks HP/VREF_64")
			(pinfunction "VREF_64")
			(pintype "input")
			(solder_mask_margin 0.075)
		)
		(pad "W19" smd circle
			(at 5.5 5.5 90)
			(size 0.5 0.5)
			(layers "F.Cu" "F.Mask" "F.Paste")
			(net 187 "/DDR5 RDIMM/A.CB7")
			(pinfunction "IO_L6P_T0U_N10_AD6P_A20_65")
			(pintype "bidirectional")
			(die_length 13.539)
			(solder_mask_margin 0.075)
		)
		(pad "W20" smd circle
			(at 6.5 5.5 90)
			(size 0.5 0.5)
			(layers "F.Cu" "F.Mask" "F.Paste")
			(net 71 "/DDR5 RDIMM/A.CB5")
			(pinfunction "IO_L6N_T0U_N11_AD6N_A21_65")
			(pintype "bidirectional")
			(die_length 11.707)
			(solder_mask_margin 0.075)
		)
		(pad "W21" smd circle
			(at 7.5 5.5 90)
			(size 0.5 0.5)
			(layers "F.Cu" "F.Mask" "F.Paste")
			(net 548 "/FPGA banks HP/VRP_65")
			(pinfunction "IO_T0U_N12_VRP_A28_65")
			(pintype "bidirectional")
			(die_length 11.222)
			(solder_mask_margin 0.075)
		)
		(pad "W22" smd circle
			(at 8.5 5.5 90)
			(size 0.5 0.5)
			(layers "F.Cu" "F.Mask" "F.Paste")
			(net 1 "GND")
			(pinfunction "GND")
			(pintype "passive")
			(solder_mask_margin 0.075)
		)
		(pad "W23" smd circle
			(at 9.5 5.5 90)
			(size 0.5 0.5)
			(layers "F.Cu" "F.Mask" "F.Paste")
			(net 74 "/DDR5 RDIMM/A.CA0")
			(pinfunction "IO_L11N_T1U_N9_GC_A11_D27_65")
			(pintype "bidirectional")
			(die_length 12.408)
			(solder_mask_margin 0.075)
		)
		(pad "W24" smd circle
			(at 10.5 5.5 90)
			(size 0.5 0.5)
			(layers "F.Cu" "F.Mask" "F.Paste")
			(net 78 "/DDR5 RDIMM/A.PAR")
			(pinfunction "IO_L12N_T1U_N11_GC_A09_D25_65")
			(pintype "bidirectional")
			(die_length 11.035)
			(solder_mask_margin 0.075)
		)
		(pad "W25" smd circle
			(at 11.5 5.5 90)
			(size 0.5 0.5)
			(layers "F.Cu" "F.Mask" "F.Paste")
			(net 634 "/DDR5 RDIMM/CTRL.CK_P")
			(pinfunction "IO_L10P_T1U_N6_QBC_AD4P_A12_D28_65")
			(pintype "bidirectional")
			(die_length 12.878)
			(solder_mask_margin 0.075)
		)
		(pad "W26" smd circle
			(at 12.5 5.5 90)
			(size 0.5 0.5)
			(layers "F.Cu" "F.Mask" "F.Paste")
			(net 633 "/DDR5 RDIMM/CTRL.CK_N")
			(pinfunction "IO_L10N_T1U_N7_QBC_AD4N_A13_D29_65")
			(pintype "bidirectional")
			(die_length 12.877)
			(solder_mask_margin 0.075)
		)
		(pad "Y1" smd circle
			(at -12.5 6.5 90)
			(size 0.5 0.5)
			(layers "F.Cu" "F.Mask" "F.Paste")
			(net 339 "/FPGA MGT Interface/PCIE.RXD3_N")
			(pinfunction "MGTYRXN0_225")
			(pintype "input")
			(die_length 11.557)
			(solder_mask_margin 0.075)
		)
		(pad "Y2" smd circle
			(at -11.5 6.5 90)
			(size 0.5 0.5)
			(layers "F.Cu" "F.Mask" "F.Paste")
			(net 338 "/FPGA MGT Interface/PCIE.RXD3_P")
			(pinfunction "MGTYRXP0_225")
			(pintype "input")
			(die_length 11.548)
			(solder_mask_margin 0.075)
		)
		(pad "Y3" smd circle
			(at -10.5 6.5 90)
			(size 0.5 0.5)
			(layers "F.Cu" "F.Mask" "F.Paste")
			(net 1 "GND")
			(pinfunction "GND")
			(pintype "passive")
			(solder_mask_margin 0.075)
		)
		(pad "Y4" smd circle
			(at -9.5 6.5 90)
			(size 0.5 0.5)
			(layers "F.Cu" "F.Mask" "F.Paste")
			(net 1 "GND")
			(pinfunction "GND")
			(pintype "passive")
			(solder_mask_margin 0.075)
		)
		(pad "Y5" smd circle
			(at -8.5 6.5 90)
			(size 0.5 0.5)
			(layers "F.Cu" "F.Mask" "F.Paste")
			(net 172 "+1V2_MGTAVTT")
			(pinfunction "MGTAVTT_R")
			(pintype "passive")
			(solder_mask_margin 0.075)
		)
		(pad "Y6" smd circle
			(at -7.5 6.5 90)
			(size 0.5 0.5)
			(layers "F.Cu" "F.Mask" "F.Paste")
			(net 569 "unconnected-(U34I-MGTREFCLK1N_224-PadY6)")
			(pinfunction "MGTREFCLK1N_224")
			(pintype "input+no_connect")
			(die_length 8.854)
			(solder_mask_margin 0.075)
		)
		(pad "Y7" smd circle
			(at -6.5 6.5 90)
			(size 0.5 0.5)
			(layers "F.Cu" "F.Mask" "F.Paste")
			(net 570 "unconnected-(U34I-MGTREFCLK1P_224-PadY7)")
			(pinfunction "MGTREFCLK1P_224")
			(pintype "input+no_connect")
			(die_length 8.9)
			(solder_mask_margin 0.075)
		)
		(pad "Y8" smd circle
			(at -5.5 6.5 90)
			(size 0.5 0.5)
			(layers "F.Cu" "F.Mask" "F.Paste")
			(net 1 "GND")
			(pinfunction "GND")
			(pintype "passive")
			(solder_mask_margin 0.075)
		)
		(pad "Y9" smd circle
			(at -4.5 6.5 90)
			(size 0.5 0.5)
			(layers "F.Cu" "F.Mask" "F.Paste")
			(net 797 "+1V8")
			(pinfunction "VBATT")
			(pintype "power_in")
			(die_length 10.352)
			(solder_mask_margin 0.075)
		)
		(pad "Y10" smd circle
			(at -3.5 6.5 90)
			(size 0.5 0.5)
			(layers "F.Cu" "F.Mask" "F.Paste")
			(net 242 "/Debug FTDI + VNA/JTAG.TDO")
			(pinfunction "TDO_0")
			(pintype "output")
			(die_length 14.323)
			(solder_mask_margin 0.075)
		)
		(pad "Y11" smd circle
			(at -2.5 6.5 90)
			(size 0.5 0.5)
			(layers "F.Cu" "F.Mask" "F.Paste")
			(net 355 "/FPGA Config/FLASH.SCK")
			(pinfunction "CCLK_0")
			(pintype "bidirectional")
			(die_length 12.313)
			(solder_mask_margin 0.075)
		)
		(pad "Y12" smd circle
			(at -1.5 6.5 90)
			(size 0.5 0.5)
			(layers "F.Cu" "F.Mask" "F.Paste")
			(net 462 "/FPGA Config/POR_OVERRIDE")
			(pinfunction "POR_OVERRIDE")
			(pintype "input")
			(die_length 14.069)
			(solder_mask_margin 0.075)
		)
		(pad "Y13" smd circle
			(at -0.5 6.5 90)
			(size 0.5 0.5)
			(layers "F.Cu" "F.Mask" "F.Paste")
			(net 571 "unconnected-(U34F-IO_L11P_AD1P_84-PadY13)")
			(pinfunction "IO_L11P_AD1P_84")
			(pintype "bidirectional+no_connect")
			(die_length 13.346)
			(solder_mask_margin 0.075)
		)
		(pad "Y14" smd circle
			(at 0.5 6.5 90)
			(size 0.5 0.5)
			(layers "F.Cu" "F.Mask" "F.Paste")
			(net 151 "+3V3")
			(pinfunction "VCCO_84")
			(pintype "passive")
			(solder_mask_margin 0.075)
		)
		(pad "Y15" smd circle
			(at 1.5 6.5 90)
			(size 0.5 0.5)
			(layers "F.Cu" "F.Mask" "F.Paste")
			(net 185 "FPGA_POWER_OFF")
			(pinfunction "IO_L7P_HDGC_AD5P_84")
			(pintype "bidirectional")
			(die_length 12.09)
			(solder_mask_margin 0.075)
		)
		(pad "Y16" smd circle
			(at 2.5 6.5 90)
			(size 0.5 0.5)
			(layers "F.Cu" "F.Mask" "F.Paste")
			(net 572 "unconnected-(U34F-IO_L9N_AD3N_84-PadY16)")
			(pinfunction "IO_L9N_AD3N_84")
			(pintype "bidirectional+no_connect")
			(die_length 10.715)
			(solder_mask_margin 0.075)
		)
		(pad "Y17" smd circle
			(at 3.5 6.5 90)
			(size 0.5 0.5)
			(layers "F.Cu" "F.Mask" "F.Paste")
			(net 135 "/DDR5 RDIMM/A.DQ7")
			(pinfunction "IO_L23P_T3U_N8_64")
			(pintype "bidirectional")
			(die_length 14.175)
			(solder_mask_margin 0.075)
		)
		(pad "Y18" smd circle
			(at 4.5 6.5 90)
			(size 0.5 0.5)
			(layers "F.Cu" "F.Mask" "F.Paste")
			(net 54 "/DDR5 RDIMM/A.DQ5")
			(pinfunction "IO_L24P_T3U_N10_64")
			(pintype "bidirectional")
			(die_length 16.052)
			(solder_mask_margin 0.075)
		)
		(pad "Y19" smd circle
			(at 5.5 6.5 90)
			(size 0.5 0.5)
			(layers "F.Cu" "F.Mask" "F.Paste")
			(net 1 "GND")
			(pinfunction "GND")
			(pintype "passive")
			(solder_mask_margin 0.075)
		)
		(pad "Y20" smd circle
			(at 6.5 6.5 90)
			(size 0.5 0.5)
			(layers "F.Cu" "F.Mask" "F.Paste")
			(net 94 "/DDR5 RDIMM/A.DQS0_P")
			(pinfunction "IO_L19P_T3L_N0_DBC_AD9P_64")
			(pintype "bidirectional")
			(die_length 12.396)
			(solder_mask_margin 0.075)
		)
		(pad "Y21" smd circle
			(at 7.5 6.5 90)
			(size 0.5 0.5)
			(layers "F.Cu" "F.Mask" "F.Paste")
			(net 101 "/DDR5 RDIMM/A.DQS0_N")
			(pinfunction "IO_L19N_T3L_N1_DBC_AD9N_64")
			(pintype "bidirectional")
			(die_length 12.493)
			(solder_mask_margin 0.075)
		)
		(pad "Y22" smd circle
			(at 8.5 6.5 90)
			(size 0.5 0.5)
			(layers "F.Cu" "F.Mask" "F.Paste")
			(net 73 "/DDR5 RDIMM/A.CS0_c")
			(pinfunction "IO_L7P_T1L_N0_QBC_AD13P_A18_65")
			(pintype "bidirectional")
			(die_length 12.981)
			(solder_mask_margin 0.075)
		)
	)
)
